(kicad_pcb
	(version 20221018)
	(generator pcbnew)
	(general
    (thickness 1.562)
  )
	(paper "A4")
	(title_block
    (title "Thunderbolt PCIe Adaper")
    (date "2024-07-09")
    (rev "1.0.3")
    (comment 1 "www.antmicro.com")
    (comment 2 "Antmicro Ltd.")
		(comment 9 "footprints 160-167 of 271")
	)
	(layers
    (0 "F.Cu" signal)
    (1 "In1.Cu" signal)
    (2 "In2.Cu" signal)
    (3 "In3.Cu" signal)
    (4 "In4.Cu" signal)
    (31 "B.Cu" signal)
    (32 "B.Adhes" user "B.Adhesive")
    (33 "F.Adhes" user "F.Adhesive")
    (34 "B.Paste" user)
    (35 "F.Paste" user)
    (36 "B.SilkS" user "B.Silkscreen")
    (37 "F.SilkS" user "F.Silkscreen")
    (38 "B.Mask" user)
    (39 "F.Mask" user)
    (40 "Dwgs.User" user "User.Drawings")
    (41 "Cmts.User" user "User.Comments")
    (42 "Eco1.User" user "User.Eco1")
    (43 "Eco2.User" user "User.Eco2")
    (44 "Edge.Cuts" user)
    (45 "Margin" user)
    (46 "B.CrtYd" user "B.Courtyard")
    (47 "F.CrtYd" user "F.Courtyard")
    (48 "B.Fab" user)
    (49 "F.Fab" user)
  )
	(footprint "antmicro-footprints:C_0402_1005Metric" (layer "B.Cu")
    (at 130.9 80.825)
    (descr "Capacitor SMD 0402")
    (tags "capacitor SMD 0402")
    (property "Author" "Antmicro")
    (property "Dielectric" "")
    (property "License" "Apache-2.0")
    (property "MPN" "C1005X6S1A105K050BC")
    (property "Manufacturer" "TDK")
    (property "Sheetfile" "tb-power.kicad_sch")
    (property "Sheetname" "Thunderbolt Controller - Power")
    (property "Val" "1u")
    (property "Voltage" "")
    (property "ki_description" "SMD Multilayer Ceramic Capacitor, 1 µF, 10 V, 0402 [1005 Metric], ± 10%, X6S, C")
    (property "ki_keywords" "0402, SMT, CAPACITOR, PASSIVE, CERAMIC, MLCC")
    (attr smd)
    (fp_text reference "C58" (at 17.309 7.567 180) (layer "B.SilkS")
        (effects (font (size 0.7 0.7) (thickness 0.15)) (justify left bottom mirror))
    )
    (fp_text value "C_1u_0402" (at -1.022927 -2.155213 180) (layer "B.Fab")
        (effects (font (size 0.7 0.7) (thickness 0.15)) (justify left bottom mirror))
    )
    (fp_text user "${REFERENCE}" (at -0.939 -4.599 180) (layer "B.Fab") hide
        (effects (font (size 0.7 0.7) (thickness 0.15)) (justify left bottom mirror))
    )
    (fp_text user "License: Apache-2.0" (at -0.939 -5.799 180) (layer "B.Fab") hide
        (effects (font (size 0.7 0.7) (thickness 0.15)) (justify left bottom mirror))
    )
    (fp_text user "Author: Antmicro" (at -0.939 -3.399 180) (layer "B.Fab") hide
        (effects (font (size 0.7 0.7) (thickness 0.15)) (justify left bottom mirror))
    )
    (fp_rect (start -0.925 0.47) (end 0.925 -0.47)
      (stroke (width 0.05) (type default)) (fill none) (layer "B.CrtYd"))
    (fp_line (start -0.494 -0.248) (end -0.494 0.25)
      (stroke (width 0.15) (type solid)) (layer "B.Fab"))
    (fp_line (start -0.494 0.25) (end 0.504 0.25)
      (stroke (width 0.15) (type solid)) (layer "B.Fab"))
    (fp_line (start 0.504 -0.248) (end -0.494 -0.248)
      (stroke (width 0.15) (type solid)) (layer "B.Fab"))
    (fp_line (start 0.504 0.25) (end 0.504 -0.248)
      (stroke (width 0.15) (type solid)) (layer "B.Fab"))
    (pad "1" smd roundrect (at -0.48 0) (size 0.59 0.64) (layers "B.Cu" "B.Paste" "B.Mask") (roundrect_rratio 0.25)
      (net 1 "GND") (pintype "passive"))
    (pad "2" smd roundrect (at 0.48 0) (size 0.59 0.64) (layers "B.Cu" "B.Paste" "B.Mask") (roundrect_rratio 0.25)
      (net 106 "Net-(C53-Pad2)") (pintype "passive"))
  )
	(footprint "antmicro-footprints:C_0402_1005Metric" (layer "B.Cu")
    (at 134.8 83.75)
    (descr "Capacitor SMD 0402")
    (tags "capacitor SMD 0402")
    (property "Author" "Antmicro")
    (property "Dielectric" "")
    (property "License" "Apache-2.0")
    (property "MPN" "C1005X6S1A105K050BC")
    (property "Manufacturer" "TDK")
    (property "Sheetfile" "tb-power.kicad_sch")
    (property "Sheetname" "Thunderbolt Controller - Power")
    (property "Val" "1u")
    (property "Voltage" "")
    (property "ki_description" "SMD Multilayer Ceramic Capacitor, 1 µF, 10 V, 0402 [1005 Metric], ± 10%, X6S, C")
    (property "ki_keywords" "0402, SMT, CAPACITOR, PASSIVE, CERAMIC, MLCC")
    (attr smd)
    (fp_text reference "C65" (at 17.6 7.649 180) (layer "B.SilkS")
        (effects (font (size 0.7 0.7) (thickness 0.15)) (justify left bottom mirror))
    )
    (fp_text value "C_1u_0402" (at -1.022927 -2.155213 180) (layer "B.Fab")
        (effects (font (size 0.7 0.7) (thickness 0.15)) (justify left bottom mirror))
    )
    (fp_text user "Author: Antmicro" (at -0.939 -3.399 180) (layer "B.Fab") hide
        (effects (font (size 0.7 0.7) (thickness 0.15)) (justify left bottom mirror))
    )
    (fp_text user "${REFERENCE}" (at -0.939 -4.599 180) (layer "B.Fab") hide
        (effects (font (size 0.7 0.7) (thickness 0.15)) (justify left bottom mirror))
    )
    (fp_text user "License: Apache-2.0" (at -0.939 -5.799 180) (layer "B.Fab") hide
        (effects (font (size 0.7 0.7) (thickness 0.15)) (justify left bottom mirror))
    )
    (fp_rect (start -0.925 0.47) (end 0.925 -0.47)
      (stroke (width 0.05) (type default)) (fill none) (layer "B.CrtYd"))
    (fp_line (start -0.494 -0.248) (end -0.494 0.25)
      (stroke (width 0.15) (type solid)) (layer "B.Fab"))
    (fp_line (start -0.494 0.25) (end 0.504 0.25)
      (stroke (width 0.15) (type solid)) (layer "B.Fab"))
    (fp_line (start 0.504 -0.248) (end -0.494 -0.248)
      (stroke (width 0.15) (type solid)) (layer "B.Fab"))
    (fp_line (start 0.504 0.25) (end 0.504 -0.248)
      (stroke (width 0.15) (type solid)) (layer "B.Fab"))
    (pad "1" smd roundrect (at -0.48 0) (size 0.59 0.64) (layers "B.Cu" "B.Paste" "B.Mask") (roundrect_rratio 0.25)
      (net 1 "GND") (pintype "passive"))
    (pad "2" smd roundrect (at 0.48 0) (size 0.59 0.64) (layers "B.Cu" "B.Paste" "B.Mask") (roundrect_rratio 0.25)
      (net 108 "Net-(C56-Pad2)") (pintype "passive"))
  )
	(footprint "antmicro-footprints:C_0402_1005Metric" (layer "B.Cu")
    (at 132.85 77.9)
    (descr "Capacitor SMD 0402")
    (tags "capacitor SMD 0402")
    (property "Author" "Antmicro")
    (property "Dielectric" "")
    (property "License" "Apache-2.0")
    (property "MPN" "C1005X6S1A105K050BC")
    (property "Manufacturer" "TDK")
    (property "Sheetfile" "tb-power.kicad_sch")
    (property "Sheetname" "Thunderbolt Controller - Power")
    (property "Val" "1u")
    (property "Voltage" "")
    (property "ki_description" "SMD Multilayer Ceramic Capacitor, 1 µF, 10 V, 0402 [1005 Metric], ± 10%, X6S, C")
    (property "ki_keywords" "0402, SMT, CAPACITOR, PASSIVE, CERAMIC, MLCC")
    (attr smd)
    (fp_text reference "C54" (at 17.518 7.571 180) (layer "B.SilkS")
        (effects (font (size 0.7 0.7) (thickness 0.15)) (justify left bottom mirror))
    )
    (fp_text value "C_1u_0402" (at -1.022927 -2.155213 180) (layer "B.Fab")
        (effects (font (size 0.7 0.7) (thickness 0.15)) (justify left bottom mirror))
    )
    (fp_text user "Author: Antmicro" (at -0.939 -3.399 180) (layer "B.Fab") hide
        (effects (font (size 0.7 0.7) (thickness 0.15)) (justify left bottom mirror))
    )
    (fp_text user "${REFERENCE}" (at -0.939 -4.599 180) (layer "B.Fab") hide
        (effects (font (size 0.7 0.7) (thickness 0.15)) (justify left bottom mirror))
    )
    (fp_text user "License: Apache-2.0" (at -0.939 -5.799 180) (layer "B.Fab") hide
        (effects (font (size 0.7 0.7) (thickness 0.15)) (justify left bottom mirror))
    )
    (fp_rect (start -0.925 0.47) (end 0.925 -0.47)
      (stroke (width 0.05) (type default)) (fill none) (layer "B.CrtYd"))
    (fp_line (start -0.494 -0.248) (end -0.494 0.25)
      (stroke (width 0.15) (type solid)) (layer "B.Fab"))
    (fp_line (start -0.494 0.25) (end 0.504 0.25)
      (stroke (width 0.15) (type solid)) (layer "B.Fab"))
    (fp_line (start 0.504 -0.248) (end -0.494 -0.248)
      (stroke (width 0.15) (type solid)) (layer "B.Fab"))
    (fp_line (start 0.504 0.25) (end 0.504 -0.248)
      (stroke (width 0.15) (type solid)) (layer "B.Fab"))
    (pad "1" smd roundrect (at -0.48 0) (size 0.59 0.64) (layers "B.Cu" "B.Paste" "B.Mask") (roundrect_rratio 0.25)
      (net 1 "GND") (pintype "passive"))
    (pad "2" smd roundrect (at 0.48 0) (size 0.59 0.64) (layers "B.Cu" "B.Paste" "B.Mask") (roundrect_rratio 0.25)
      (net 107 "Net-(C54-Pad2)") (pintype "passive"))
  )
	(footprint "antmicro-footprints:C_0402_1005Metric" (layer "B.Cu")
    (at 138.7 77.9 180)
    (descr "Capacitor SMD 0402")
    (tags "capacitor SMD 0402")
    (property "Author" "Antmicro")
    (property "Dielectric" "")
    (property "License" "Apache-2.0")
    (property "MPN" "C1005X6S1A105K050BC")
    (property "Manufacturer" "TDK")
    (property "Sheetfile" "tb-power.kicad_sch")
    (property "Sheetname" "Thunderbolt Controller - Power")
    (property "Val" "1u")
    (property "Voltage" "")
    (property "ki_description" "SMD Multilayer Ceramic Capacitor, 1 µF, 10 V, 0402 [1005 Metric], ± 10%, X6S, C")
    (property "ki_keywords" "0402, SMT, CAPACITOR, PASSIVE, CERAMIC, MLCC")
    (attr smd)
    (fp_text reference "C73" (at -17.764 -7.952) (layer "B.SilkS")
        (effects (font (size 0.7 0.7) (thickness 0.15)) (justify left bottom mirror))
    )
    (fp_text value "C_1u_0402" (at -1.022927 -2.155213) (layer "B.Fab")
        (effects (font (size 0.7 0.7) (thickness 0.15)) (justify left bottom mirror))
    )
    (fp_text user "${REFERENCE}" (at -0.939 -4.599) (layer "B.Fab") hide
        (effects (font (size 0.7 0.7) (thickness 0.15)) (justify left bottom mirror))
    )
    (fp_text user "License: Apache-2.0" (at -0.939 -5.799) (layer "B.Fab") hide
        (effects (font (size 0.7 0.7) (thickness 0.15)) (justify left bottom mirror))
    )
    (fp_text user "Author: Antmicro" (at -0.939 -3.399) (layer "B.Fab") hide
        (effects (font (size 0.7 0.7) (thickness 0.15)) (justify left bottom mirror))
    )
    (fp_rect (start -0.925 0.47) (end 0.925 -0.47)
      (stroke (width 0.05) (type default)) (fill none) (layer "B.CrtYd"))
    (fp_line (start -0.494 -0.248) (end -0.494 0.25)
      (stroke (width 0.15) (type solid)) (layer "B.Fab"))
    (fp_line (start -0.494 0.25) (end 0.504 0.25)
      (stroke (width 0.15) (type solid)) (layer "B.Fab"))
    (fp_line (start 0.504 -0.248) (end -0.494 -0.248)
      (stroke (width 0.15) (type solid)) (layer "B.Fab"))
    (fp_line (start 0.504 0.25) (end 0.504 -0.248)
      (stroke (width 0.15) (type solid)) (layer "B.Fab"))
    (pad "1" smd roundrect (at -0.48 0 180) (size 0.59 0.64) (layers "B.Cu" "B.Paste" "B.Mask") (roundrect_rratio 0.25)
      (net 1 "GND") (pintype "passive"))
    (pad "2" smd roundrect (at 0.48 0 180) (size 0.59 0.64) (layers "B.Cu" "B.Paste" "B.Mask") (roundrect_rratio 0.25)
      (net 2 "3V3_SYS") (pintype "passive"))
  )
	(footprint "antmicro-footprints:C_0402_1005Metric" (layer "B.Cu")
    (at 134.8 82.775)
    (descr "Capacitor SMD 0402")
    (tags "capacitor SMD 0402")
    (property "Author" "Antmicro")
    (property "Dielectric" "")
    (property "License" "Apache-2.0")
    (property "MPN" "C1005X6S1A105K050BC")
    (property "Manufacturer" "TDK")
    (property "Sheetfile" "tb-power.kicad_sch")
    (property "Sheetname" "Thunderbolt Controller - Power")
    (property "Val" "1u")
    (property "Voltage" "")
    (property "ki_description" "SMD Multilayer Ceramic Capacitor, 1 µF, 10 V, 0402 [1005 Metric], ± 10%, X6S, C")
    (property "ki_keywords" "0402, SMT, CAPACITOR, PASSIVE, CERAMIC, MLCC")
    (attr smd)
    (fp_text reference "C62" (at 17.6 7.649 180) (layer "B.SilkS")
        (effects (font (size 0.7 0.7) (thickness 0.15)) (justify left bottom mirror))
    )
    (fp_text value "C_1u_0402" (at -1.022927 -2.155213 180) (layer "B.Fab")
        (effects (font (size 0.7 0.7) (thickness 0.15)) (justify left bottom mirror))
    )
    (fp_text user "License: Apache-2.0" (at -0.939 -5.799 180) (layer "B.Fab") hide
        (effects (font (size 0.7 0.7) (thickness 0.15)) (justify left bottom mirror))
    )
    (fp_text user "Author: Antmicro" (at -0.939 -3.399 180) (layer "B.Fab") hide
        (effects (font (size 0.7 0.7) (thickness 0.15)) (justify left bottom mirror))
    )
    (fp_text user "${REFERENCE}" (at -0.939 -4.599 180) (layer "B.Fab") hide
        (effects (font (size 0.7 0.7) (thickness 0.15)) (justify left bottom mirror))
    )
    (fp_rect (start -0.925 0.47) (end 0.925 -0.47)
      (stroke (width 0.05) (type default)) (fill none) (layer "B.CrtYd"))
    (fp_line (start -0.494 -0.248) (end -0.494 0.25)
      (stroke (width 0.15) (type solid)) (layer "B.Fab"))
    (fp_line (start -0.494 0.25) (end 0.504 0.25)
      (stroke (width 0.15) (type solid)) (layer "B.Fab"))
    (fp_line (start 0.504 -0.248) (end -0.494 -0.248)
      (stroke (width 0.15) (type solid)) (layer "B.Fab"))
    (fp_line (start 0.504 0.25) (end 0.504 -0.248)
      (stroke (width 0.15) (type solid)) (layer "B.Fab"))
    (pad "1" smd roundrect (at -0.48 0) (size 0.59 0.64) (layers "B.Cu" "B.Paste" "B.Mask") (roundrect_rratio 0.25)
      (net 1 "GND") (pintype "passive"))
    (pad "2" smd roundrect (at 0.48 0) (size 0.59 0.64) (layers "B.Cu" "B.Paste" "B.Mask") (roundrect_rratio 0.25)
      (net 108 "Net-(C56-Pad2)") (pintype "passive"))
  )
	(footprint "antmicro-footprints:C_0402_1005Metric" (layer "B.Cu")
    (at 108.915 83.67 180)
    (descr "Capacitor SMD 0402")
    (tags "capacitor SMD 0402")
    (property "Author" "Antmicro")
    (property "Dielectric" "")
    (property "License" "Apache-2.0")
    (property "MPN" "CC0402KRX5R6BB224")
    (property "Manufacturer" "YAGEO")
    (property "Sheetfile" "power.kicad_sch")
    (property "Sheetname" "Power")
    (property "Val" "220n")
    (property "Voltage" "")
    (property "ki_description" "SMD Multilayer Ceramic Capacitor, 0.22 µF, 10 V, 0402 [1005 Metric], ± 10%, X5R, CC Series")
    (property "ki_keywords" "0402, SMT, CAPACITOR, PASSIVE, MLCC, CERAMIC")
    (attr smd)
    (fp_text reference "C16" (at -1.067 5.692) (layer "B.SilkS")
        (effects (font (size 0.7 0.7) (thickness 0.15)) (justify left bottom mirror))
    )
    (fp_text value "C_220n_0402" (at -1.022927 -2.155213) (layer "B.Fab")
        (effects (font (size 0.7 0.7) (thickness 0.15)) (justify left bottom mirror))
    )
    (fp_text user "${REFERENCE}" (at -0.939 -4.599) (layer "B.Fab") hide
        (effects (font (size 0.7 0.7) (thickness 0.15)) (justify left bottom mirror))
    )
    (fp_text user "License: Apache-2.0" (at -0.939 -5.799) (layer "B.Fab") hide
        (effects (font (size 0.7 0.7) (thickness 0.15)) (justify left bottom mirror))
    )
    (fp_text user "Author: Antmicro" (at -0.939 -3.399) (layer "B.Fab") hide
        (effects (font (size 0.7 0.7) (thickness 0.15)) (justify left bottom mirror))
    )
    (fp_rect (start -0.925 0.47) (end 0.925 -0.47)
      (stroke (width 0.05) (type default)) (fill none) (layer "B.CrtYd"))
    (fp_line (start -0.494 -0.248) (end -0.494 0.25)
      (stroke (width 0.15) (type solid)) (layer "B.Fab"))
    (fp_line (start -0.494 0.25) (end 0.504 0.25)
      (stroke (width 0.15) (type solid)) (layer "B.Fab"))
    (fp_line (start 0.504 -0.248) (end -0.494 -0.248)
      (stroke (width 0.15) (type solid)) (layer "B.Fab"))
    (fp_line (start 0.504 0.25) (end 0.504 -0.248)
      (stroke (width 0.15) (type solid)) (layer "B.Fab"))
    (pad "1" smd roundrect (at -0.48 0 180) (size 0.59 0.64) (layers "B.Cu" "B.Paste" "B.Mask") (roundrect_rratio 0.25)
      (net 1 "GND") (pintype "passive"))
    (pad "2" smd roundrect (at 0.48 0 180) (size 0.59 0.64) (layers "B.Cu" "B.Paste" "B.Mask") (roundrect_rratio 0.25)
      (net 5 "Net-(U1-VREF)") (pintype "passive"))
  )
	(footprint "antmicro-footprints:R_0402_1005Metric" (layer "B.Cu")
    (at 137.225 70.72 90)
    (descr "Resistor SMD 0402")
    (tags "resistor SMD 0402")
    (property "Author" "Antmicro")
    (property "License" "Apache-2.0")
    (property "MPN" "CR0402-FX-1002GLF")
    (property "Manufacturer" "Bourns")
    (property "Sheetfile" "tb.kicad_sch")
    (property "Sheetname" "TB Controller")
    (property "Tolerance" "1%")
    (property "Val" "10k")
    (property "ki_description" "SMD Chip Resistor, 10 kohm, ± 1%, 62.5 mW, 0402 [1005 Metric], Thick Film, General Purpose")
    (property "ki_keywords" "0402, SMT, RESISTOR, PASSIVE")
    (attr smd)
    (fp_text reference "R83" (at -1.035 0.434 270) (layer "B.SilkS")
        (effects (font (size 0.7 0.7) (thickness 0.15)) (justify left bottom mirror))
    )
    (fp_text value "R_10k_0402" (at -1.011843 -1.772047 270) (layer "B.Fab")
        (effects (font (size 0.7 0.7) (thickness 0.15)) (justify left bottom mirror))
    )
    (fp_text user "Author: Antmicro" (at -0.95 -4.169 270) (layer "B.Fab") hide
        (effects (font (size 0.7 0.7) (thickness 0.15)) (justify left bottom mirror))
    )
    (fp_text user "${REFERENCE}" (at -0.95 -3.168 270) (layer "B.Fab") hide
        (effects (font (size 0.7 0.7) (thickness 0.15)) (justify left bottom mirror))
    )
    (fp_text user "License: Apache-2.0" (at -0.95 -5.169 270) (layer "B.Fab") hide
        (effects (font (size 0.7 0.7) (thickness 0.15)) (justify left bottom mirror))
    )
    (fp_rect (start -0.925 0.47) (end 0.925 -0.47)
      (stroke (width 0.05) (type default)) (fill none) (layer "B.CrtYd"))
    (fp_rect (start -0.5 0.25) (end 0.5 -0.25)
      (stroke (width 0.15) (type solid)) (fill none) (layer "B.Fab"))
    (pad "1" smd roundrect (at -0.48 0 90) (size 0.59 0.64) (layers "B.Cu" "B.Paste" "B.Mask") (roundrect_rratio 0.25)
      (net 198 "Net-(U4C-POC_GPIO_1)") (pintype "passive"))
    (pad "2" smd roundrect (at 0.48 0 90) (size 0.59 0.64) (layers "B.Cu" "B.Paste" "B.Mask") (roundrect_rratio 0.25)
      (net 2 "3V3_SYS") (pintype "passive"))
  )
	(footprint "antmicro-footprints:C_0402_1005Metric" (layer "B.Cu")
    (at 134.8 80.825 180)
    (descr "Capacitor SMD 0402")
    (tags "capacitor SMD 0402")
    (property "Author" "Antmicro")
    (property "Dielectric" "")
    (property "License" "Apache-2.0")
    (property "MPN" "C1005X6S1A105K050BC")
    (property "Manufacturer" "TDK")
    (property "Sheetfile" "tb-power.kicad_sch")
    (property "Sheetname" "Thunderbolt Controller - Power")
    (property "Val" "1u")
    (property "Voltage" "")
    (property "ki_description" "SMD Multilayer Ceramic Capacitor, 1 µF, 10 V, 0402 [1005 Metric], ± 10%, X6S, C")
    (property "ki_keywords" "0402, SMT, CAPACITOR, PASSIVE, CERAMIC, MLCC")
    (attr smd)
    (fp_text reference "C56" (at -17.6 -7.694) (layer "B.SilkS")
        (effects (font (size 0.7 0.7) (thickness 0.15)) (justify left bottom mirror))
    )
    (fp_text value "C_1u_0402" (at -1.022927 -2.155213) (layer "B.Fab")
        (effects (font (size 0.7 0.7) (thickness 0.15)) (justify left bottom mirror))
    )
    (fp_text user "License: Apache-2.0" (at -0.939 -5.799) (layer "B.Fab") hide
        (effects (font (size 0.7 0.7) (thickness 0.15)) (justify left bottom mirror))
    )
    (fp_text user "${REFERENCE}" (at -0.939 -4.599) (layer "B.Fab") hide
        (effects (font (size 0.7 0.7) (thickness 0.15)) (justify left bottom mirror))
    )
    (fp_text user "Author: Antmicro" (at -0.939 -3.399) (layer "B.Fab") hide
        (effects (font (size 0.7 0.7) (thickness 0.15)) (justify left bottom mirror))
    )
    (fp_rect (start -0.925 0.47) (end 0.925 -0.47)
      (stroke (width 0.05) (type default)) (fill none) (layer "B.CrtYd"))
    (fp_line (start -0.494 -0.248) (end -0.494 0.25)
      (stroke (width 0.15) (type solid)) (layer "B.Fab"))
    (fp_line (start -0.494 0.25) (end 0.504 0.25)
      (stroke (width 0.15) (type solid)) (layer "B.Fab"))
    (fp_line (start 0.504 -0.248) (end -0.494 -0.248)
      (stroke (width 0.15) (type solid)) (layer "B.Fab"))
    (fp_line (start 0.504 0.25) (end 0.504 -0.248)
      (stroke (width 0.15) (type solid)) (layer "B.Fab"))
    (pad "1" smd roundrect (at -0.48 0 180) (size 0.59 0.64) (layers "B.Cu" "B.Paste" "B.Mask") (roundrect_rratio 0.25)
      (net 1 "GND") (pintype "passive"))
    (pad "2" smd roundrect (at 0.48 0 180) (size 0.59 0.64) (layers "B.Cu" "B.Paste" "B.Mask") (roundrect_rratio 0.25)
      (net 108 "Net-(C56-Pad2)") (pintype "passive"))
  )
)
